(kicad_pcb
	(version 20260206)
	(generator "pcbnew")
	(generator_version "10.0")
	(general
		(thickness 1.6)
		(legacy_teardrops no)
	)
	(paper "A4")
	(title_block
		(title "baseboard — 13948-1b.1110WZS1818.brd")
		(comment 1 "Honey Badger (Wiwynn) / footprints 110-116 of 2523")
	)
	(layers
		(0 "F.Cu" signal "TOP")
		(4 "In1.Cu" signal "L2GND")
		(6 "In2.Cu" signal "L3")
		(8 "In3.Cu" signal "L4VCC")
		(10 "In4.Cu" signal "L5VCC")
		(12 "In5.Cu" signal "L6")
		(14 "In6.Cu" signal "L7GND")
		(2 "B.Cu" signal "BOTTOM")
		(9 "F.Adhes" user "F.Adhesive")
		(11 "B.Adhes" user "B.Adhesive")
		(13 "F.Paste" user "Package Geometry/Pastemask Top")
		(15 "B.Paste" user "Package Geometry/Pastemask Bottom")
		(5 "F.SilkS" user "Ref Des/Silkscreen Top")
		(7 "B.SilkS" user "Ref Des/Silkscreen Bottom")
		(1 "F.Mask" user "Board Geometry/Soldermask Top")
		(3 "B.Mask" user "Board Geometry/Soldermask Bottom")
		(17 "Dwgs.User" user "User.Drawings")
		(19 "Cmts.User" user "User.Comments")
		(21 "Eco1.User" user "User.Eco1")
		(23 "Eco2.User" user "User.Eco2")
		(25 "Edge.Cuts" user "Board Geometry/Outline")
		(27 "Margin" user)
		(31 "F.CrtYd" user "Package Geometry/Place Bound Top")
		(29 "B.CrtYd" user "Package Geometry/Place Bound Bottom")
		(35 "F.Fab" user "Ref Des/Assembly Top")
		(33 "B.Fab" user "Ref Des/Assembly Bottom")
	)
	(footprint ""
		(layer "F.Cu")
		(at 21.159216 -213.79688 180)
		(property "Reference" "SR306"
			(at 0 0 180)
			(layer "F.SilkS")
			(hide yes)
			(effects
				(font
					(size 1.27 1.27)
				)
			)
		)
		(property "Value" "0R2J-2-GP"
			(at 0.064008 -3.993896 180)
			(unlocked yes)
			(layer "F.Fab")
			(hide yes)
			(effects
				(font
					(size 1.016 1.016)
					(thickness 0.1524)
				)
			)
		)
		(property "Device Type" "R402H16"
			(at 0.064008 -5.517896 180)
			(unlocked yes)
			(layer "F.Fab")
			(hide yes)
			(effects
				(font
					(size 1.016 1.016)
					(thickness 0.1524)
				)
			)
		)
		(duplicate_pad_numbers_are_jumpers no)
		(fp_line
			(start 0.508 -0.9398)
			(end -0.508 -0.9398)
			(stroke
				(width 0.1524)
				(type default)
			)
			(layer "F.SilkS")
		)
		(fp_line
			(start -0.508 -0.9398)
			(end -0.508 0.9398)
			(stroke
				(width 0.1524)
				(type default)
			)
			(layer "F.SilkS")
		)
		(fp_rect
			(start -0.508 0.9398)
			(end 0.508 -0.9398)
			(stroke
				(width 0)
				(type default)
			)
			(fill no)
			(layer "F.CrtYd")
		)
		(fp_rect
			(start -0.508 0.9398)
			(end 0.508 -0.9398)
			(stroke
				(width 0)
				(type default)
			)
			(fill no)
			(layer "F.Fab")
		)
		(pad "1" smd custom
			(at 0 -0.4445 180)
			(size 0.1397 0.1397)
			(layers "F.Cu" "F.Mask" "F.Paste")
			(net "HDD_PWR_RESET_N")
			(options
				(clearance outline)
				(anchor circle)
			)
			(primitives
				(gr_poly
					(pts
						(arc
							(start -0.1778 -0.2794)
							(mid -0.249642 -0.249642)
							(end -0.2794 -0.1778)
						)
						(arc
							(start -0.2794 0.1778)
							(mid -0.249642 0.249642)
							(end -0.1778 0.2794)
						)
						(arc
							(start 0.1778 0.2794)
							(mid 0.249642 0.249642)
							(end 0.2794 0.1778)
						)
						(arc
							(start 0.2794 -0.1778)
							(mid 0.249642 -0.249642)
							(end 0.1778 -0.2794)
						)
					)
					(width 0)
					(fill yes)
				)
			)
		)
		(pad "2" smd custom
			(at 0 0.4445 180)
			(size 0.1397 0.1397)
			(layers "F.Cu" "F.Mask" "F.Paste")
			(net "I2C_IO_EXP_RESET#_PWR")
			(options
				(clearance outline)
				(anchor circle)
			)
			(primitives
				(gr_poly
					(pts
						(arc
							(start -0.1778 -0.2794)
							(mid -0.249642 -0.249642)
							(end -0.2794 -0.1778)
						)
						(arc
							(start -0.2794 0.1778)
							(mid -0.249642 0.249642)
							(end -0.1778 0.2794)
						)
						(arc
							(start 0.1778 0.2794)
							(mid 0.249642 0.249642)
							(end 0.2794 0.1778)
						)
						(arc
							(start 0.2794 -0.1778)
							(mid 0.249642 -0.249642)
							(end 0.1778 -0.2794)
						)
					)
					(width 0)
					(fill yes)
				)
			)
		)
	)
	(footprint ""
		(layer "F.Cu")
		(at 62.357 -219.329 -90)
		(property "Reference" "R1227"
			(at 0 0 270)
			(layer "F.SilkS")
			(hide yes)
			(effects
				(font
					(size 1.27 1.27)
				)
			)
		)
		(property "Value" "100KR2F-L1-GP"
			(at 0.064008 -3.993896 270)
			(unlocked yes)
			(layer "F.Fab")
			(hide yes)
			(effects
				(font
					(size 1.016 1.016)
					(thickness 0.1524)
				)
			)
		)
		(property "Device Type" "R402H16"
			(at 0.064008 -5.517896 270)
			(unlocked yes)
			(layer "F.Fab")
			(hide yes)
			(effects
				(font
					(size 1.016 1.016)
					(thickness 0.1524)
				)
			)
		)
		(duplicate_pad_numbers_are_jumpers no)
		(fp_line
			(start -0.508 -0.9398)
			(end -0.508 0.9398)
			(stroke
				(width 0.1524)
				(type default)
			)
			(layer "F.SilkS")
		)
		(fp_line
			(start 0.508 -0.9398)
			(end -0.508 -0.9398)
			(stroke
				(width 0.1524)
				(type default)
			)
			(layer "F.SilkS")
		)
		(fp_rect
			(start -0.508 0.9398)
			(end 0.508 -0.9398)
			(stroke
				(width 0)
				(type default)
			)
			(fill no)
			(layer "F.CrtYd")
		)
		(fp_rect
			(start -0.508 0.9398)
			(end 0.508 -0.9398)
			(stroke
				(width 0)
				(type default)
			)
			(fill no)
			(layer "F.Fab")
		)
		(pad "1" smd custom
			(at 0 -0.4445 270)
			(size 0.1397 0.1397)
			(layers "F.Cu" "F.Mask" "F.Paste")
			(net "P12V")
			(options
				(clearance outline)
				(anchor circle)
			)
			(primitives
				(gr_poly
					(pts
						(arc
							(start -0.1778 -0.2794)
							(mid -0.249642 -0.249642)
							(end -0.2794 -0.1778)
						)
						(arc
							(start -0.2794 0.1778)
							(mid -0.249642 0.249642)
							(end -0.1778 0.2794)
						)
						(arc
							(start 0.1778 0.2794)
							(mid 0.249642 0.249642)
							(end 0.2794 0.1778)
						)
						(arc
							(start 0.2794 -0.1778)
							(mid 0.249642 -0.249642)
							(end 0.1778 -0.2794)
						)
					)
					(width 0)
					(fill yes)
				)
			)
		)
		(pad "2" smd custom
			(at 0 0.4445 270)
			(size 0.1397 0.1397)
			(layers "F.Cu" "F.Mask" "F.Paste")
			(net "MB0_P12V_PWGIN_R")
			(options
				(clearance outline)
				(anchor circle)
			)
			(primitives
				(gr_poly
					(pts
						(arc
							(start -0.1778 -0.2794)
							(mid -0.249642 -0.249642)
							(end -0.2794 -0.1778)
						)
						(arc
							(start -0.2794 0.1778)
							(mid -0.249642 0.249642)
							(end -0.1778 0.2794)
						)
						(arc
							(start 0.1778 0.2794)
							(mid 0.249642 0.249642)
							(end 0.2794 0.1778)
						)
						(arc
							(start 0.2794 -0.1778)
							(mid 0.249642 -0.249642)
							(end 0.1778 -0.2794)
						)
					)
					(width 0)
					(fill yes)
				)
			)
		)
	)
	(footprint ""
		(layer "F.Cu")
		(at 86.49716 -45.212 -90)
		(property "Reference" "SC902"
			(at 0 0 270)
			(layer "F.SilkS")
			(hide yes)
			(effects
				(font
					(size 1.27 1.27)
				)
			)
		)
		(property "Value" "SCD01U10V1KX-GP"
			(at -2.8321 -1.7399 270)
			(unlocked yes)
			(layer "F.Fab")
			(hide yes)
			(effects
				(font
					(size 1.016 1.016)
					(thickness 0.1524)
				)
			)
		)
		(property "Device Type" "C0201H13"
			(at -2.8321 -3.2639 270)
			(unlocked yes)
			(layer "F.Fab")
			(hide yes)
			(effects
				(font
					(size 1.016 1.016)
					(thickness 0.1524)
				)
			)
		)
		(duplicate_pad_numbers_are_jumpers no)
		(fp_rect
			(start -0.2794 0.6477)
			(end 0.2794 -0.6477)
			(stroke
				(width 0)
				(type default)
			)
			(fill no)
			(layer "F.CrtYd")
		)
		(fp_rect
			(start -0.2794 0.6477)
			(end 0.2794 -0.6477)
			(stroke
				(width 0)
				(type default)
			)
			(fill no)
			(layer "F.Fab")
		)
		(pad "1" smd custom
			(at 0 -0.2794 270)
			(size 0.0762 0.0762)
			(layers "F.Cu" "F.Mask" "F.Paste")
			(net "SAS3008_RAID_TX_C_P4")
			(options
				(clearance outline)
				(anchor circle)
			)
			(primitives
				(gr_poly
					(pts
						(arc
							(start 0.1524 -0.127)
							(mid 0.137521 -0.162921)
							(end 0.1016 -0.1778)
						)
						(arc
							(start -0.1016 -0.1778)
							(mid -0.137521 -0.162921)
							(end -0.1524 -0.127)
						)
						(arc
							(start -0.1524 0.127)
							(mid -0.137521 0.162921)
							(end -0.1016 0.1778)
						)
						(arc
							(start 0.1016 0.1778)
							(mid 0.137521 0.162921)
							(end 0.1524 0.127)
						)
					)
					(width 0)
					(fill yes)
				)
			)
		)
		(pad "2" smd custom
			(at 0 0.2794 270)
			(size 0.0762 0.0762)
			(layers "F.Cu" "F.Mask" "F.Paste")
			(net "IOC_RAID_TX_P4")
			(options
				(clearance outline)
				(anchor circle)
			)
			(primitives
				(gr_poly
					(pts
						(arc
							(start 0.1524 -0.127)
							(mid 0.137521 -0.162921)
							(end 0.1016 -0.1778)
						)
						(arc
							(start -0.1016 -0.1778)
							(mid -0.137521 -0.162921)
							(end -0.1524 -0.127)
						)
						(arc
							(start -0.1524 0.127)
							(mid -0.137521 0.162921)
							(end -0.1016 0.1778)
						)
						(arc
							(start 0.1016 0.1778)
							(mid 0.137521 0.162921)
							(end 0.1524 0.127)
						)
					)
					(width 0)
					(fill yes)
				)
			)
		)
	)
	(footprint ""
		(layer "F.Cu")
		(at 289.687 -68.707 90)
		(property "Reference" "PR9001"
			(at 0 0 90)
			(layer "F.SilkS")
			(hide yes)
			(effects
				(font
					(size 1.27 1.27)
				)
			)
		)
		(property "Value" "0R2J-2-GP"
			(at 0.064008 -3.993896 90)
			(unlocked yes)
			(layer "F.Fab")
			(hide yes)
			(effects
				(font
					(size 1.016 1.016)
					(thickness 0.1524)
				)
			)
		)
		(property "Device Type" "R402H16"
			(at 0.064008 -5.517896 90)
			(unlocked yes)
			(layer "F.Fab")
			(hide yes)
			(effects
				(font
					(size 1.016 1.016)
					(thickness 0.1524)
				)
			)
		)
		(duplicate_pad_numbers_are_jumpers no)
		(fp_line
			(start 0.508 -0.9398)
			(end -0.508 -0.9398)
			(stroke
				(width 0.1524)
				(type default)
			)
			(layer "F.SilkS")
		)
		(fp_line
			(start -0.508 -0.9398)
			(end -0.508 0.9398)
			(stroke
				(width 0.1524)
				(type default)
			)
			(layer "F.SilkS")
		)
		(fp_rect
			(start -0.508 0.9398)
			(end 0.508 -0.9398)
			(stroke
				(width 0)
				(type default)
			)
			(fill no)
			(layer "F.CrtYd")
		)
		(fp_rect
			(start -0.508 0.9398)
			(end 0.508 -0.9398)
			(stroke
				(width 0)
				(type default)
			)
			(fill no)
			(layer "F.Fab")
		)
		(pad "1" smd custom
			(at 0 -0.4445 90)
			(size 0.1397 0.1397)
			(layers "F.Cu" "F.Mask" "F.Paste")
			(net "HSW_SDA1")
			(options
				(clearance outline)
				(anchor circle)
			)
			(primitives
				(gr_poly
					(pts
						(arc
							(start -0.1778 -0.2794)
							(mid -0.249642 -0.249642)
							(end -0.2794 -0.1778)
						)
						(arc
							(start -0.2794 0.1778)
							(mid -0.249642 0.249642)
							(end -0.1778 0.2794)
						)
						(arc
							(start 0.1778 0.2794)
							(mid 0.249642 0.249642)
							(end 0.2794 0.1778)
						)
						(arc
							(start 0.2794 -0.1778)
							(mid 0.249642 -0.249642)
							(end 0.1778 -0.2794)
						)
					)
					(width 0)
					(fill yes)
				)
			)
		)
		(pad "2" smd custom
			(at 0 0.4445 90)
			(size 0.1397 0.1397)
			(layers "F.Cu" "F.Mask" "F.Paste")
			(net "BMC_I2C_A_SDA")
			(options
				(clearance outline)
				(anchor circle)
			)
			(primitives
				(gr_poly
					(pts
						(arc
							(start -0.1778 -0.2794)
							(mid -0.249642 -0.249642)
							(end -0.2794 -0.1778)
						)
						(arc
							(start -0.2794 0.1778)
							(mid -0.249642 0.249642)
							(end -0.1778 0.2794)
						)
						(arc
							(start 0.1778 0.2794)
							(mid 0.249642 0.249642)
							(end 0.2794 0.1778)
						)
						(arc
							(start 0.2794 -0.1778)
							(mid 0.249642 -0.249642)
							(end 0.1778 -0.2794)
						)
					)
					(width 0)
					(fill yes)
				)
			)
		)
	)
	(footprint ""
		(layer "F.Cu")
		(at 79.4766 -13.1318 90)
		(property "Reference" "PC211"
			(at 0 0 90)
			(layer "F.SilkS")
			(hide yes)
			(effects
				(font
					(size 1.27 1.27)
				)
			)
		)
		(property "Value" "SCD01U50V3KX-4GP"
			(at 0 -2.8194 90)
			(unlocked yes)
			(layer "F.Fab")
			(hide yes)
			(effects
				(font
					(size 1.016 1.016)
					(thickness 0.1524)
				)
			)
		)
		(property "Device Type" "C603H36"
			(at 0 -4.3434 90)
			(unlocked yes)
			(layer "F.Fab")
			(hide yes)
			(effects
				(font
					(size 1.016 1.016)
					(thickness 0.1524)
				)
			)
		)
		(duplicate_pad_numbers_are_jumpers no)
		(fp_line
			(start 0.508 0)
			(end -0.508 0)
			(stroke
				(width 0.2032)
				(type default)
			)
			(layer "F.SilkS")
		)
		(fp_rect
			(start -0.5842 1.3335)
			(end 0.5842 -1.3335)
			(stroke
				(width 0)
				(type default)
			)
			(fill no)
			(layer "F.CrtYd")
		)
		(fp_rect
			(start -0.5842 1.3335)
			(end 0.5842 -1.3335)
			(stroke
				(width 0)
				(type default)
			)
			(fill no)
			(layer "F.Fab")
		)
		(pad "1" smd custom
			(at 0 -0.762 90)
			(size 0.2159 0.2159)
			(layers "F.Cu" "F.Mask" "F.Paste")
			(net "VT235_VDDH")
			(options
				(clearance outline)
				(anchor circle)
			)
			(primitives
				(gr_poly
					(pts
						(arc
							(start -0.3302 -0.4318)
							(mid -0.402042 -0.402042)
							(end -0.4318 -0.3302)
						)
						(arc
							(start -0.4318 0.3302)
							(mid -0.402042 0.402042)
							(end -0.3302 0.4318)
						)
						(arc
							(start 0.3302 0.4318)
							(mid 0.402042 0.402042)
							(end 0.4318 0.3302)
						)
						(arc
							(start 0.4318 -0.3302)
							(mid 0.402042 -0.402042)
							(end 0.3302 -0.4318)
						)
					)
					(width 0)
					(fill yes)
				)
			)
		)
		(pad "2" smd custom
			(at 0 0.762 90)
			(size 0.2159 0.2159)
			(layers "F.Cu" "F.Mask" "F.Paste")
			(net "GND")
			(options
				(clearance outline)
				(anchor circle)
			)
			(primitives
				(gr_poly
					(pts
						(arc
							(start -0.3302 -0.4318)
							(mid -0.402042 -0.402042)
							(end -0.4318 -0.3302)
						)
						(arc
							(start -0.4318 0.3302)
							(mid -0.402042 0.402042)
							(end -0.3302 0.4318)
						)
						(arc
							(start 0.3302 0.4318)
							(mid 0.402042 0.402042)
							(end 0.4318 0.3302)
						)
						(arc
							(start 0.4318 -0.3302)
							(mid 0.402042 -0.402042)
							(end 0.3302 -0.4318)
						)
					)
					(width 0)
					(fill yes)
				)
			)
		)
	)
	(footprint ""
		(layer "F.Cu")
		(at 133.736842 -84.526882 90)
		(property "Reference" "SC1096"
			(at 0 0 90)
			(layer "F.SilkS")
			(hide yes)
			(effects
				(font
					(size 1.27 1.27)
				)
			)
		)
		(property "Value" "SCD01U10V1KX-GP"
			(at -2.8321 -1.7399 90)
			(unlocked yes)
			(layer "F.Fab")
			(hide yes)
			(effects
				(font
					(size 1.016 1.016)
					(thickness 0.1524)
				)
			)
		)
		(property "Device Type" "C0201H13"
			(at -2.8321 -3.2639 90)
			(unlocked yes)
			(layer "F.Fab")
			(hide yes)
			(effects
				(font
					(size 1.016 1.016)
					(thickness 0.1524)
				)
			)
		)
		(duplicate_pad_numbers_are_jumpers no)
		(fp_rect
			(start -0.2794 0.6477)
			(end 0.2794 -0.6477)
			(stroke
				(width 0)
				(type default)
			)
			(fill no)
			(layer "F.CrtYd")
		)
		(fp_rect
			(start -0.2794 0.6477)
			(end 0.2794 -0.6477)
			(stroke
				(width 0)
				(type default)
			)
			(fill no)
			(layer "F.Fab")
		)
		(pad "1" smd custom
			(at 0 -0.2794 90)
			(size 0.0762 0.0762)
			(layers "F.Cu" "F.Mask" "F.Paste")
			(net "SAS_HDD_TX14_P")
			(options
				(clearance outline)
				(anchor circle)
			)
			(primitives
				(gr_poly
					(pts
						(arc
							(start 0.1524 -0.127)
							(mid 0.137521 -0.162921)
							(end 0.1016 -0.1778)
						)
						(arc
							(start -0.1016 -0.1778)
							(mid -0.137521 -0.162921)
							(end -0.1524 -0.127)
						)
						(arc
							(start -0.1524 0.127)
							(mid -0.137521 0.162921)
							(end -0.1016 0.1778)
						)
						(arc
							(start 0.1016 0.1778)
							(mid 0.137521 0.162921)
							(end 0.1524 0.127)
						)
					)
					(width 0)
					(fill yes)
				)
			)
		)
		(pad "2" smd custom
			(at 0 0.2794 90)
			(size 0.0762 0.0762)
			(layers "F.Cu" "F.Mask" "F.Paste")
			(net "3008_SAS_RX_P2")
			(options
				(clearance outline)
				(anchor circle)
			)
			(primitives
				(gr_poly
					(pts
						(arc
							(start 0.1524 -0.127)
							(mid 0.137521 -0.162921)
							(end 0.1016 -0.1778)
						)
						(arc
							(start -0.1016 -0.1778)
							(mid -0.137521 -0.162921)
							(end -0.1524 -0.127)
						)
						(arc
							(start -0.1524 0.127)
							(mid -0.137521 0.162921)
							(end -0.1016 0.1778)
						)
						(arc
							(start 0.1016 0.1778)
							(mid 0.137521 0.162921)
							(end 0.1524 0.127)
						)
					)
					(width 0)
					(fill yes)
				)
			)
		)
	)
	(footprint ""
		(layer "F.Cu")
		(at 333.066136 -206.002128)
		(property "Reference" "U16"
			(at 0 0 0)
			(layer "F.SilkS")
			(hide yes)
			(effects
				(font
					(size 1.27 1.27)
				)
			)
		)
		(property "Value" "24LC64-I-SN-GP"
			(at -3.707384 -1.5367 0)
			(unlocked yes)
			(layer "F.Fab")
			(hide yes)
			(effects
				(font
					(size 1.016 1.016)
					(thickness 0.1524)
				)
			)
		)
		(property "Device Type" "SOIC8H69"
			(at -3.707384 -3.0607 0)
			(unlocked yes)
			(layer "F.Fab")
			(hide yes)
			(effects
				(font
					(size 1.016 1.016)
					(thickness 0.1524)
				)
			)
		)
		(duplicate_pad_numbers_are_jumpers no)
		(fp_line
			(start -2.7432 -1.4224)
			(end -2.7432 1.4224)
			(stroke
				(width 0.1524)
				(type default)
			)
			(layer "F.SilkS")
		)
		(fp_line
			(start -2.7432 1.4224)
			(end -2.6416 1.4224)
			(stroke
				(width 0.1524)
				(type default)
			)
			(layer "F.SilkS")
		)
		(fp_line
			(start -2.7432 1.4224)
			(end 2.1336 1.4224)
			(stroke
				(width 0.1524)
				(type default)
			)
			(layer "F.SilkS")
		)
		(fp_line
			(start -2.7178 -0.508)
			(end -2.1844 -0.0508)
			(stroke
				(width 0.1524)
				(type default)
			)
			(layer "F.SilkS")
		)
		(fp_line
			(start -2.6289 3.4417)
			(end -2.6289 1.4732)
			(stroke
				(width 0.381)
				(type default)
			)
			(layer "F.SilkS")
		)
		(fp_line
			(start -2.1844 -0.0508)
			(end -2.7178 0.508)
			(stroke
				(width 0.1524)
				(type default)
			)
			(layer "F.SilkS")
		)
		(fp_line
			(start 2.1336 -1.4224)
			(end -2.7432 -1.4224)
			(stroke
				(width 0.1524)
				(type default)
			)
			(layer "F.SilkS")
		)
		(fp_line
			(start 2.1336 1.4224)
			(end 2.1336 -1.4224)
			(stroke
				(width 0.1524)
				(type default)
			)
			(layer "F.SilkS")
		)
		(fp_poly
			(pts
				(xy -2.2098 -1.4224) (xy -2.2098 1.4224) (xy 2.2098 1.4224) (xy 2.2098 -1.4224)
			)
			(stroke
				(width 0)
				(type default)
			)
			(fill yes)
			(layer "F.SilkS")
		)
		(fp_rect
			(start -2.450084 2.999994)
			(end 2.450084 -2.999994)
			(stroke
				(width 0)
				(type default)
			)
			(fill no)
			(layer "F.CrtYd")
		)
		(fp_poly
			(pts
				(xy -2.8194 3.6322) (xy -2.8194 -3.6322) (xy 2.8194 -3.6322) (xy 2.8194 1.18364) (xy 2.450084 1.18364)
				(xy 2.450084 -2.999994) (xy -2.450084 -2.999994) (xy -2.450084 2.999994) (xy 2.450084 2.999994)
				(xy 2.450084 1.18618) (xy 2.8194 1.18618) (xy 2.8194 3.6322)
			)
			(stroke
				(width 0)
				(type default)
			)
			(fill no)
			(layer "F.CrtYd")
		)
		(fp_rect
			(start -2.8194 3.6322)
			(end 2.8194 -3.6322)
			(stroke
				(width 0)
				(type default)
			)
			(fill no)
			(layer "F.Fab")
		)
		(pad "1" smd rect
			(at -1.905 2.54)
			(size 0.635 1.651)
			(layers "F.Cu" "F.Mask" "F.Paste")
			(net "EEPROM_A0_R")
		)
		(pad "2" smd rect
			(at -0.635 2.54)
			(size 0.635 1.651)
			(layers "F.Cu" "F.Mask" "F.Paste")
			(net "EEPROM_A1_R")
		)
		(pad "3" smd rect
			(at 0.635 2.54)
			(size 0.635 1.651)
			(layers "F.Cu" "F.Mask" "F.Paste")
			(net "EEPROM_A2_R")
		)
		(pad "4" smd rect
			(at 1.905 2.54)
			(size 0.635 1.651)
			(layers "F.Cu" "F.Mask" "F.Paste")
			(net "GND")
		)
		(pad "5" smd rect
			(at 1.905 -2.54)
			(size 0.635 1.651)
			(layers "F.Cu" "F.Mask" "F.Paste")
			(net "EEPROM_SDA")
		)
		(pad "6" smd rect
			(at 0.635 -2.54)
			(size 0.635 1.651)
			(layers "F.Cu" "F.Mask" "F.Paste")
			(net "EEPROM_SCL")
		)
		(pad "7" smd rect
			(at -0.635 -2.54)
			(size 0.635 1.651)
			(layers "F.Cu" "F.Mask" "F.Paste")
			(net "EEPROM_WP")
		)
		(pad "8" smd rect
			(at -1.905 -2.54)
			(size 0.635 1.651)
			(layers "F.Cu" "F.Mask" "F.Paste")
			(net "P3V3_STBY")
		)
	)
)
